(kicad_pcb
	(version 20260206)
	(generator "pcbnew")
	(generator_version "10.0")
	(general
		(thickness 1.6)
		(legacy_teardrops no)
	)
	(paper "A4")
	(title_block
		(title "01162023_DA0F0TEBIF0_F0T_Expander_BD_F_brd_V02_OCP.brd")
		(comment 1 "Grand Teton / footprints 5419-5421 of 9728")
	)
	(layers
		(0 "F.Cu" signal "TOP")
		(4 "In1.Cu" signal "GND")
		(6 "In2.Cu" signal "VCC")
		(8 "In3.Cu" signal "VCC1")
		(10 "In4.Cu" signal "GND1")
		(12 "In5.Cu" signal "IN1")
		(14 "In6.Cu" signal "GND2")
		(16 "In7.Cu" signal "IN2")
		(18 "In8.Cu" signal "GND3")
		(20 "In9.Cu" signal "IN3")
		(22 "In10.Cu" signal "GND4")
		(24 "In11.Cu" signal "IN4")
		(26 "In12.Cu" signal "GND5")
		(28 "In13.Cu" signal "IN5")
		(30 "In14.Cu" signal "GND6")
		(32 "In15.Cu" signal "IN6")
		(34 "In16.Cu" signal "GND7")
		(2 "B.Cu" signal "BOTTOM")
		(9 "F.Adhes" user "F.Adhesive")
		(11 "B.Adhes" user "B.Adhesive")
		(13 "F.Paste" user "Package Geometry/Pastemask Top")
		(15 "B.Paste" user "Package Geometry/Pastemask Bottom")
		(5 "F.SilkS" user "Ref Des/Silkscreen Top")
		(7 "B.SilkS" user "Ref Des/Silkscreen Bottom")
		(1 "F.Mask" user "Board Geometry/Soldermask Top")
		(3 "B.Mask" user "Board Geometry/Soldermask Bottom")
		(17 "Dwgs.User" user "User.Drawings")
		(19 "Cmts.User" user "User.Comments")
		(21 "Eco1.User" user "User.Eco1")
		(23 "Eco2.User" user "User.Eco2")
		(25 "Edge.Cuts" user "Board Geometry/Outline")
		(27 "Margin" user)
		(31 "F.CrtYd" user "Package Geometry/Place Bound Top")
		(29 "B.CrtYd" user "Package Geometry/Place Bound Bottom")
		(35 "F.Fab" user "Ref Des/Assembly Top")
		(33 "B.Fab" user "Ref Des/Assembly Bottom")
	)
	(footprint ""
		(layer "F.Cu")
		(at 400.543776 -48.93691 180)
		(property "Reference" "R655"
			(at 0 0 180)
			(layer "F.SilkS")
			(hide yes)
			(effects
				(font
					(size 1.27 1.27)
				)
			)
		)
		(property "Value" ""
			(at 0 0 180)
			(layer "F.Fab")
			(effects
				(font
					(size 1.27 1.27)
				)
			)
		)
		(duplicate_pad_numbers_are_jumpers no)
		(fp_line
			(start 0.7874 0.4064)
			(end -0.7874 0.4064)
			(stroke
				(width 0.1524)
				(type default)
			)
			(layer "F.SilkS")
		)
		(fp_line
			(start 0.7874 -0.4064)
			(end 0.7874 0.4064)
			(stroke
				(width 0.1524)
				(type default)
			)
			(layer "F.SilkS")
		)
		(fp_line
			(start -0.7874 0.4064)
			(end -0.7874 -0.4064)
			(stroke
				(width 0.1524)
				(type default)
			)
			(layer "F.SilkS")
		)
		(fp_line
			(start -0.7874 -0.4064)
			(end 0.7874 -0.4064)
			(stroke
				(width 0.1524)
				(type default)
			)
			(layer "F.SilkS")
		)
		(fp_line
			(start 0.67945 0.3048)
			(end 0.120396 0.3048)
			(stroke
				(width 0.1)
				(type default)
			)
			(layer "F.Fab")
		)
		(fp_line
			(start 0.67945 -0.3048)
			(end 0.67945 0.3048)
			(stroke
				(width 0.1)
				(type default)
			)
			(layer "F.Fab")
		)
		(fp_line
			(start 0.12065 -0.2794)
			(end 0.12065 -0.3048)
			(stroke
				(width 0.1)
				(type default)
			)
			(layer "F.Fab")
		)
		(fp_line
			(start 0.12065 -0.3048)
			(end 0.67945 -0.3048)
			(stroke
				(width 0.1)
				(type default)
			)
			(layer "F.Fab")
		)
		(fp_line
			(start 0.120396 0.3048)
			(end 0.120396 0.2794)
			(stroke
				(width 0.1)
				(type default)
			)
			(layer "F.Fab")
		)
		(fp_line
			(start 0.120396 0.2794)
			(end -0.12065 0.2794)
			(stroke
				(width 0.1)
				(type default)
			)
			(layer "F.Fab")
		)
		(fp_line
			(start -0.12065 0.3048)
			(end -0.67945 0.3048)
			(stroke
				(width 0.1)
				(type default)
			)
			(layer "F.Fab")
		)
		(fp_line
			(start -0.12065 0.2794)
			(end -0.12065 0.3048)
			(stroke
				(width 0.1)
				(type default)
			)
			(layer "F.Fab")
		)
		(fp_line
			(start -0.12065 -0.2794)
			(end 0.12065 -0.2794)
			(stroke
				(width 0.1)
				(type default)
			)
			(layer "F.Fab")
		)
		(fp_line
			(start -0.12065 -0.305054)
			(end -0.12065 -0.2794)
			(stroke
				(width 0.1)
				(type default)
			)
			(layer "F.Fab")
		)
		(fp_line
			(start -0.67945 0.3048)
			(end -0.67945 -0.305054)
			(stroke
				(width 0.1)
				(type default)
			)
			(layer "F.Fab")
		)
		(fp_line
			(start -0.67945 -0.305054)
			(end -0.12065 -0.305054)
			(stroke
				(width 0.1)
				(type default)
			)
			(layer "F.Fab")
		)
		(pad "1" smd circle
			(at -0.40005 0 180)
			(size 0 0)
			(layers "F.Cu" "F.Mask" "F.Paste")
			(net "SMB_BIC_I2C6_MUX_SSD_8_15_ADC_R_SDA")
		)
		(pad "2" smd circle
			(at 0.40005 0 180)
			(size 0 0)
			(layers "F.Cu" "F.Mask" "F.Paste")
			(net "SMB_SSD13_ADC_SDA")
		)
	)
	(footprint ""
		(layer "F.Cu")
		(at 440.838844 -122.798332 90)
		(property "Reference" "PC490"
			(at 0 0 90)
			(layer "F.SilkS")
			(hide yes)
			(effects
				(font
					(size 1.27 1.27)
				)
			)
		)
		(property "Value" ""
			(at 0 0 90)
			(layer "F.Fab")
			(effects
				(font
					(size 1.27 1.27)
				)
			)
		)
		(duplicate_pad_numbers_are_jumpers no)
		(fp_line
			(start 0.7874 -0.4064)
			(end 0.7874 0.4064)
			(stroke
				(width 0.1524)
				(type default)
			)
			(layer "F.SilkS")
		)
		(fp_line
			(start -0.7874 -0.4064)
			(end 0.7874 -0.4064)
			(stroke
				(width 0.1524)
				(type default)
			)
			(layer "F.SilkS")
		)
		(fp_line
			(start 0.7874 0.4064)
			(end -0.7874 0.4064)
			(stroke
				(width 0.1524)
				(type default)
			)
			(layer "F.SilkS")
		)
		(fp_line
			(start -0.7874 0.4064)
			(end -0.7874 -0.4064)
			(stroke
				(width 0.1524)
				(type default)
			)
			(layer "F.SilkS")
		)
		(fp_line
			(start -0.12065 -0.305054)
			(end -0.12065 -0.2794)
			(stroke
				(width 0.1)
				(type default)
			)
			(layer "F.Fab")
		)
		(fp_line
			(start -0.67945 -0.305054)
			(end -0.12065 -0.305054)
			(stroke
				(width 0.1)
				(type default)
			)
			(layer "F.Fab")
		)
		(fp_line
			(start 0.67945 -0.3048)
			(end 0.67945 0.3048)
			(stroke
				(width 0.1)
				(type default)
			)
			(layer "F.Fab")
		)
		(fp_line
			(start 0.12065 -0.3048)
			(end 0.67945 -0.3048)
			(stroke
				(width 0.1)
				(type default)
			)
			(layer "F.Fab")
		)
		(fp_line
			(start 0.12065 -0.2794)
			(end 0.12065 -0.3048)
			(stroke
				(width 0.1)
				(type default)
			)
			(layer "F.Fab")
		)
		(fp_line
			(start -0.12065 -0.2794)
			(end 0.12065 -0.2794)
			(stroke
				(width 0.1)
				(type default)
			)
			(layer "F.Fab")
		)
		(fp_line
			(start 0.120396 0.2794)
			(end -0.12065 0.2794)
			(stroke
				(width 0.1)
				(type default)
			)
			(layer "F.Fab")
		)
		(fp_line
			(start -0.12065 0.2794)
			(end -0.12065 0.3048)
			(stroke
				(width 0.1)
				(type default)
			)
			(layer "F.Fab")
		)
		(fp_line
			(start 0.67945 0.3048)
			(end 0.120396 0.3048)
			(stroke
				(width 0.1)
				(type default)
			)
			(layer "F.Fab")
		)
		(fp_line
			(start 0.120396 0.3048)
			(end 0.120396 0.2794)
			(stroke
				(width 0.1)
				(type default)
			)
			(layer "F.Fab")
		)
		(fp_line
			(start -0.12065 0.3048)
			(end -0.67945 0.3048)
			(stroke
				(width 0.1)
				(type default)
			)
			(layer "F.Fab")
		)
		(fp_line
			(start -0.67945 0.3048)
			(end -0.67945 -0.305054)
			(stroke
				(width 0.1)
				(type default)
			)
			(layer "F.Fab")
		)
		(pad "1" smd circle
			(at -0.40005 0 90)
			(size 0 0)
			(layers "F.Cu" "F.Mask" "F.Paste")
			(net "P3V3_NIC7")
		)
		(pad "2" smd circle
			(at 0.40005 0 90)
			(size 0 0)
			(layers "F.Cu" "F.Mask" "F.Paste")
			(net "GND")
		)
	)
	(footprint ""
		(layer "F.Cu")
		(at 342.835738 -111.896906 90)
		(property "Reference" "PR7034"
			(at 0 0 90)
			(layer "F.SilkS")
			(hide yes)
			(effects
				(font
					(size 1.27 1.27)
				)
			)
		)
		(property "Value" ""
			(at 0 0 90)
			(layer "F.Fab")
			(effects
				(font
					(size 1.27 1.27)
				)
			)
		)
		(duplicate_pad_numbers_are_jumpers no)
		(fp_line
			(start 0.7874 -0.4064)
			(end 0.7874 0.4064)
			(stroke
				(width 0.1524)
				(type default)
			)
			(layer "F.SilkS")
		)
		(fp_line
			(start -0.7874 -0.4064)
			(end 0.7874 -0.4064)
			(stroke
				(width 0.1524)
				(type default)
			)
			(layer "F.SilkS")
		)
		(fp_line
			(start 0.7874 0.4064)
			(end -0.7874 0.4064)
			(stroke
				(width 0.1524)
				(type default)
			)
			(layer "F.SilkS")
		)
		(fp_line
			(start -0.7874 0.4064)
			(end -0.7874 -0.4064)
			(stroke
				(width 0.1524)
				(type default)
			)
			(layer "F.SilkS")
		)
		(fp_line
			(start -0.12065 -0.305054)
			(end -0.12065 -0.2794)
			(stroke
				(width 0.1)
				(type default)
			)
			(layer "F.Fab")
		)
		(fp_line
			(start -0.67945 -0.305054)
			(end -0.12065 -0.305054)
			(stroke
				(width 0.1)
				(type default)
			)
			(layer "F.Fab")
		)
		(fp_line
			(start 0.67945 -0.3048)
			(end 0.67945 0.3048)
			(stroke
				(width 0.1)
				(type default)
			)
			(layer "F.Fab")
		)
		(fp_line
			(start 0.12065 -0.3048)
			(end 0.67945 -0.3048)
			(stroke
				(width 0.1)
				(type default)
			)
			(layer "F.Fab")
		)
		(fp_line
			(start 0.12065 -0.2794)
			(end 0.12065 -0.3048)
			(stroke
				(width 0.1)
				(type default)
			)
			(layer "F.Fab")
		)
		(fp_line
			(start -0.12065 -0.2794)
			(end 0.12065 -0.2794)
			(stroke
				(width 0.1)
				(type default)
			)
			(layer "F.Fab")
		)
		(fp_line
			(start 0.120396 0.2794)
			(end -0.12065 0.2794)
			(stroke
				(width 0.1)
				(type default)
			)
			(layer "F.Fab")
		)
		(fp_line
			(start -0.12065 0.2794)
			(end -0.12065 0.3048)
			(stroke
				(width 0.1)
				(type default)
			)
			(layer "F.Fab")
		)
		(fp_line
			(start 0.67945 0.3048)
			(end 0.120396 0.3048)
			(stroke
				(width 0.1)
				(type default)
			)
			(layer "F.Fab")
		)
		(fp_line
			(start 0.120396 0.3048)
			(end 0.120396 0.2794)
			(stroke
				(width 0.1)
				(type default)
			)
			(layer "F.Fab")
		)
		(fp_line
			(start -0.12065 0.3048)
			(end -0.67945 0.3048)
			(stroke
				(width 0.1)
				(type default)
			)
			(layer "F.Fab")
		)
		(fp_line
			(start -0.67945 0.3048)
			(end -0.67945 -0.305054)
			(stroke
				(width 0.1)
				(type default)
			)
			(layer "F.Fab")
		)
		(pad "1" smd circle
			(at -0.40005 0 90)
			(size 0 0)
			(layers "F.Cu" "F.Mask" "F.Paste")
			(net "P12V_NIC5_CO_ISET")
		)
		(pad "2" smd circle
			(at 0.40005 0 90)
			(size 0 0)
			(layers "F.Cu" "F.Mask" "F.Paste")
			(net "P12V_NIC5_CO_ISET_R")
		)
	)
)
